(kicad_pcb
	(version 20260206)
	(generator "pcbnew")
	(generator_version "10.0")
	(general
		(thickness 1.6)
		(legacy_teardrops no)
	)
	(paper "A4")
	(title_block
		(title "9054_F0T_PDB_BD_GPU_F_V04_1213_1550_OCP.brd")
		(comment 1 "Grand Teton / footprints 52-59 of 608")
	)
	(layers
		(0 "F.Cu" signal "TOP")
		(4 "In1.Cu" signal "GND")
		(6 "In2.Cu" signal "IN1")
		(8 "In3.Cu" signal "GND1")
		(10 "In4.Cu" signal "VCC")
		(12 "In5.Cu" signal "VCC1")
		(14 "In6.Cu" signal "GND2")
		(16 "In7.Cu" signal "IN2")
		(18 "In8.Cu" signal "GND3")
		(2 "B.Cu" signal "BOTTOM")
		(9 "F.Adhes" user "F.Adhesive")
		(11 "B.Adhes" user "B.Adhesive")
		(13 "F.Paste" user "Package Geometry/Pastemask Top")
		(15 "B.Paste" user "Package Geometry/Pastemask Bottom")
		(5 "F.SilkS" user "Ref Des/Silkscreen Top")
		(7 "B.SilkS" user "Ref Des/Silkscreen Bottom")
		(1 "F.Mask" user "Board Geometry/Soldermask Top")
		(3 "B.Mask" user "Board Geometry/Soldermask Bottom")
		(17 "Dwgs.User" user "User.Drawings")
		(19 "Cmts.User" user "User.Comments")
		(21 "Eco1.User" user "User.Eco1")
		(23 "Eco2.User" user "User.Eco2")
		(25 "Edge.Cuts" user "Board Geometry/Outline")
		(27 "Margin" user)
		(31 "F.CrtYd" user "Package Geometry/Place Bound Top")
		(29 "B.CrtYd" user "Package Geometry/Place Bound Bottom")
		(35 "F.Fab" user "Ref Des/Assembly Top")
		(33 "B.Fab" user "Ref Des/Assembly Bottom")
	)
	(footprint ""
		(layer "F.Cu")
		(at 445.741806 -92.843858 180)
		(property "Reference" "PC617"
			(at 0 0 180)
			(layer "F.SilkS")
			(hide yes)
			(effects
				(font
					(size 1.27 1.27)
				)
			)
		)
		(property "Value" ""
			(at 0 0 180)
			(layer "F.Fab")
			(effects
				(font
					(size 1.27 1.27)
				)
			)
		)
		(duplicate_pad_numbers_are_jumpers no)
		(fp_line
			(start 1.524 0.762)
			(end -1.524 0.762)
			(stroke
				(width 0.1524)
				(type default)
			)
			(layer "F.SilkS")
		)
		(fp_line
			(start 1.524 -0.762)
			(end 1.524 0.762)
			(stroke
				(width 0.1524)
				(type default)
			)
			(layer "F.SilkS")
		)
		(fp_line
			(start -1.524 0.762)
			(end -1.524 -0.762)
			(stroke
				(width 0.1524)
				(type default)
			)
			(layer "F.SilkS")
		)
		(fp_line
			(start -1.524 -0.762)
			(end 1.524 -0.762)
			(stroke
				(width 0.1524)
				(type default)
			)
			(layer "F.SilkS")
		)
		(fp_line
			(start 1.1049 0.724916)
			(end 1.1049 -0.724916)
			(stroke
				(width 0.1)
				(type default)
			)
			(layer "F.Fab")
		)
		(fp_line
			(start 1.1049 -0.724916)
			(end -1.1049 -0.724916)
			(stroke
				(width 0.1)
				(type default)
			)
			(layer "F.Fab")
		)
		(fp_line
			(start -1.1049 0.724916)
			(end 1.1049 0.724916)
			(stroke
				(width 0.1)
				(type default)
			)
			(layer "F.Fab")
		)
		(fp_line
			(start -1.1049 -0.724916)
			(end -1.1049 0.724916)
			(stroke
				(width 0.1)
				(type default)
			)
			(layer "F.Fab")
		)
		(pad "1" smd rect
			(at -0.889 0)
			(size 1.016 1.27)
			(layers "F.Cu" "F.Mask" "F.Paste")
			(net "SW_P3V3_HPDB_FLT")
		)
		(pad "2" smd rect
			(at 0.889 0)
			(size 1.016 1.27)
			(layers "F.Cu" "F.Mask" "F.Paste")
			(net "GND")
		)
	)
	(footprint ""
		(layer "F.Cu")
		(at 427.228 -41.783)
		(property "Reference" "R101"
			(at 0 0 0)
			(layer "F.SilkS")
			(hide yes)
			(effects
				(font
					(size 1.27 1.27)
				)
			)
		)
		(property "Value" ""
			(at 0 0 0)
			(layer "F.Fab")
			(effects
				(font
					(size 1.27 1.27)
				)
			)
		)
		(duplicate_pad_numbers_are_jumpers no)
		(fp_line
			(start -0.7874 -0.4064)
			(end 0.7874 -0.4064)
			(stroke
				(width 0.1524)
				(type default)
			)
			(layer "F.SilkS")
		)
		(fp_line
			(start -0.7874 0.4064)
			(end -0.7874 -0.4064)
			(stroke
				(width 0.1524)
				(type default)
			)
			(layer "F.SilkS")
		)
		(fp_line
			(start 0.7874 -0.4064)
			(end 0.7874 0.4064)
			(stroke
				(width 0.1524)
				(type default)
			)
			(layer "F.SilkS")
		)
		(fp_line
			(start 0.7874 0.4064)
			(end -0.7874 0.4064)
			(stroke
				(width 0.1524)
				(type default)
			)
			(layer "F.SilkS")
		)
		(fp_line
			(start -0.67945 -0.305054)
			(end -0.12065 -0.305054)
			(stroke
				(width 0.1)
				(type default)
			)
			(layer "F.Fab")
		)
		(fp_line
			(start -0.67945 0.3048)
			(end -0.67945 -0.305054)
			(stroke
				(width 0.1)
				(type default)
			)
			(layer "F.Fab")
		)
		(fp_line
			(start -0.12065 -0.305054)
			(end -0.12065 -0.2794)
			(stroke
				(width 0.1)
				(type default)
			)
			(layer "F.Fab")
		)
		(fp_line
			(start -0.12065 -0.2794)
			(end 0.12065 -0.2794)
			(stroke
				(width 0.1)
				(type default)
			)
			(layer "F.Fab")
		)
		(fp_line
			(start -0.12065 0.2794)
			(end -0.12065 0.3048)
			(stroke
				(width 0.1)
				(type default)
			)
			(layer "F.Fab")
		)
		(fp_line
			(start -0.12065 0.3048)
			(end -0.67945 0.3048)
			(stroke
				(width 0.1)
				(type default)
			)
			(layer "F.Fab")
		)
		(fp_line
			(start 0.120396 0.2794)
			(end -0.12065 0.2794)
			(stroke
				(width 0.1)
				(type default)
			)
			(layer "F.Fab")
		)
		(fp_line
			(start 0.120396 0.3048)
			(end 0.120396 0.2794)
			(stroke
				(width 0.1)
				(type default)
			)
			(layer "F.Fab")
		)
		(fp_line
			(start 0.12065 -0.3048)
			(end 0.67945 -0.3048)
			(stroke
				(width 0.1)
				(type default)
			)
			(layer "F.Fab")
		)
		(fp_line
			(start 0.12065 -0.2794)
			(end 0.12065 -0.3048)
			(stroke
				(width 0.1)
				(type default)
			)
			(layer "F.Fab")
		)
		(fp_line
			(start 0.67945 -0.3048)
			(end 0.67945 0.3048)
			(stroke
				(width 0.1)
				(type default)
			)
			(layer "F.Fab")
		)
		(fp_line
			(start 0.67945 0.3048)
			(end 0.120396 0.3048)
			(stroke
				(width 0.1)
				(type default)
			)
			(layer "F.Fab")
		)
		(pad "1" smd circle
			(at -0.40005 0)
			(size 0 0)
			(layers "F.Cu" "F.Mask" "F.Paste")
			(net "SKU_ID_0")
		)
		(pad "2" smd circle
			(at 0.40005 0)
			(size 0 0)
			(layers "F.Cu" "F.Mask" "F.Paste")
			(net "GND")
		)
	)
	(footprint ""
		(layer "F.Cu")
		(at 11.999976 -4.499864 180)
		(property "Reference" "H2"
			(at 0.696976 10.713466 0)
			(unlocked yes)
			(layer "F.SilkS")
			(effects
				(font
					(size 0.7874 0.5842)
					(thickness 0.1524)
				)
				(justify left)
			)
		)
		(property "Value" ""
			(at 0 0 180)
			(layer "F.Fab")
			(effects
				(font
					(size 1.27 1.27)
				)
			)
		)
		(duplicate_pad_numbers_are_jumpers no)
		(pad "1" thru_hole oval
			(at 0 0 180)
			(size 9.017 14.0208)
			(drill 3.0226
				(offset 0 2.499868)
			)
			(layers "*.Cu" "*.Mask")
			(remove_unused_layers no)
			(net "GND")
			(clearance -1.500378)
			(padstack
				(mode front_inner_back)
				(layer "Inner"
					(shape circle)
					(size 0 0)
					(clearance 0)
				)
				(layer "B.Cu"
					(shape oval)
					(size 9.017 14.0208)
					(offset 0 2.499868)
					(clearance -1.500378)
				)
			)
		)
	)
	(footprint ""
		(layer "F.Cu")
		(at 447.00952 -73.62698 -90)
		(property "Reference" "PL2"
			(at -4.85902 -7.32155 90)
			(unlocked yes)
			(layer "F.SilkS")
			(effects
				(font
					(size 0.7874 0.5842)
					(thickness 0.1524)
				)
				(justify left)
			)
		)
		(property "Value" ""
			(at 0 0 270)
			(layer "F.Fab")
			(effects
				(font
					(size 1.27 1.27)
				)
			)
		)
		(duplicate_pad_numbers_are_jumpers no)
		(fp_line
			(start -6.999986 6.400038)
			(end -6.999986 1.8923)
			(stroke
				(width 0.1524)
				(type default)
			)
			(layer "F.SilkS")
		)
		(fp_line
			(start 6.999986 6.400038)
			(end -6.999986 6.400038)
			(stroke
				(width 0.1524)
				(type default)
			)
			(layer "F.SilkS")
		)
		(fp_line
			(start 6.999986 1.8923)
			(end 6.999986 6.400038)
			(stroke
				(width 0.1524)
				(type default)
			)
			(layer "F.SilkS")
		)
		(fp_line
			(start -6.999986 -1.8923)
			(end -6.999986 -6.400038)
			(stroke
				(width 0.1524)
				(type default)
			)
			(layer "F.SilkS")
		)
		(fp_line
			(start -6.999986 -6.400038)
			(end 6.999986 -6.400038)
			(stroke
				(width 0.1524)
				(type default)
			)
			(layer "F.SilkS")
		)
		(fp_line
			(start 6.999986 -6.400038)
			(end 6.999986 -1.8923)
			(stroke
				(width 0.1524)
				(type default)
			)
			(layer "F.SilkS")
		)
		(fp_line
			(start -6.999986 6.400038)
			(end 6.999986 6.400038)
			(stroke
				(width 0.1)
				(type default)
			)
			(layer "F.Fab")
		)
		(fp_line
			(start 6.999986 6.400038)
			(end 6.999986 -6.400038)
			(stroke
				(width 0.1)
				(type default)
			)
			(layer "F.Fab")
		)
		(fp_line
			(start -6.999986 2.5146)
			(end -6.999986 6.400038)
			(stroke
				(width 0.1)
				(type default)
			)
			(layer "F.Fab")
		)
		(fp_line
			(start -6.999986 -6.400038)
			(end -6.999986 2.5146)
			(stroke
				(width 0.1)
				(type default)
			)
			(layer "F.Fab")
		)
		(fp_line
			(start 6.999986 -6.400038)
			(end -6.999986 -6.400038)
			(stroke
				(width 0.1)
				(type default)
			)
			(layer "F.Fab")
		)
		(pad "1" smd rect
			(at -5.625084 0 270)
			(size 3.2512 3.5052)
			(layers "F.Cu" "F.Mask" "F.Paste")
			(net "SW_P3V3_HPDB_PH")
		)
		(pad "2" smd rect
			(at 5.625084 0 270)
			(size 3.2512 3.5052)
			(layers "F.Cu" "F.Mask" "F.Paste")
			(net "P3V3_AUX")
		)
	)
	(footprint ""
		(layer "F.Cu")
		(at 94.6404 -34.417)
		(property "Reference" "ME5"
			(at 0 0 0)
			(layer "F.SilkS")
			(hide yes)
			(effects
				(font
					(size 1.27 1.27)
				)
			)
		)
		(property "Value" ""
			(at 0 0 0)
			(layer "F.Fab")
			(effects
				(font
					(size 1.27 1.27)
				)
			)
		)
		(duplicate_pad_numbers_are_jumpers no)
	)
	(footprint ""
		(layer "F.Cu")
		(at 52.832 -26.543 -90)
		(property "Reference" "PR103"
			(at 0 0 270)
			(layer "F.SilkS")
			(hide yes)
			(effects
				(font
					(size 1.27 1.27)
				)
			)
		)
		(property "Value" ""
			(at 0 0 270)
			(layer "F.Fab")
			(effects
				(font
					(size 1.27 1.27)
				)
			)
		)
		(duplicate_pad_numbers_are_jumpers no)
		(fp_line
			(start -0.7874 0.4064)
			(end -0.7874 -0.4064)
			(stroke
				(width 0.1524)
				(type default)
			)
			(layer "F.SilkS")
		)
		(fp_line
			(start 0.7874 0.4064)
			(end -0.7874 0.4064)
			(stroke
				(width 0.1524)
				(type default)
			)
			(layer "F.SilkS")
		)
		(fp_line
			(start -0.7874 -0.4064)
			(end 0.7874 -0.4064)
			(stroke
				(width 0.1524)
				(type default)
			)
			(layer "F.SilkS")
		)
		(fp_line
			(start 0.7874 -0.4064)
			(end 0.7874 0.4064)
			(stroke
				(width 0.1524)
				(type default)
			)
			(layer "F.SilkS")
		)
		(fp_line
			(start -0.67945 0.3048)
			(end -0.67945 -0.305054)
			(stroke
				(width 0.1)
				(type default)
			)
			(layer "F.Fab")
		)
		(fp_line
			(start -0.12065 0.3048)
			(end -0.67945 0.3048)
			(stroke
				(width 0.1)
				(type default)
			)
			(layer "F.Fab")
		)
		(fp_line
			(start 0.120396 0.3048)
			(end 0.120396 0.2794)
			(stroke
				(width 0.1)
				(type default)
			)
			(layer "F.Fab")
		)
		(fp_line
			(start 0.67945 0.3048)
			(end 0.120396 0.3048)
			(stroke
				(width 0.1)
				(type default)
			)
			(layer "F.Fab")
		)
		(fp_line
			(start -0.12065 0.2794)
			(end -0.12065 0.3048)
			(stroke
				(width 0.1)
				(type default)
			)
			(layer "F.Fab")
		)
		(fp_line
			(start 0.120396 0.2794)
			(end -0.12065 0.2794)
			(stroke
				(width 0.1)
				(type default)
			)
			(layer "F.Fab")
		)
		(fp_line
			(start -0.12065 -0.2794)
			(end 0.12065 -0.2794)
			(stroke
				(width 0.1)
				(type default)
			)
			(layer "F.Fab")
		)
		(fp_line
			(start 0.12065 -0.2794)
			(end 0.12065 -0.3048)
			(stroke
				(width 0.1)
				(type default)
			)
			(layer "F.Fab")
		)
		(fp_line
			(start 0.12065 -0.3048)
			(end 0.67945 -0.3048)
			(stroke
				(width 0.1)
				(type default)
			)
			(layer "F.Fab")
		)
		(fp_line
			(start 0.67945 -0.3048)
			(end 0.67945 0.3048)
			(stroke
				(width 0.1)
				(type default)
			)
			(layer "F.Fab")
		)
		(fp_line
			(start -0.67945 -0.305054)
			(end -0.12065 -0.305054)
			(stroke
				(width 0.1)
				(type default)
			)
			(layer "F.Fab")
		)
		(fp_line
			(start -0.12065 -0.305054)
			(end -0.12065 -0.2794)
			(stroke
				(width 0.1)
				(type default)
			)
			(layer "F.Fab")
		)
		(pad "1" smd circle
			(at -0.40005 0 270)
			(size 0 0)
			(layers "F.Cu" "F.Mask" "F.Paste")
			(net "P52V_HS2_EN")
		)
		(pad "2" smd circle
			(at 0.40005 0 270)
			(size 0 0)
			(layers "F.Cu" "F.Mask" "F.Paste")
			(net "P52V_HS2_EN_DISCHARGE")
		)
	)
	(footprint ""
		(layer "F.Cu")
		(at 306.7304 -69.977)
		(property "Reference" "PR6958"
			(at 0 0 0)
			(layer "F.SilkS")
			(hide yes)
			(effects
				(font
					(size 1.27 1.27)
				)
			)
		)
		(property "Value" ""
			(at 0 0 0)
			(layer "F.Fab")
			(effects
				(font
					(size 1.27 1.27)
				)
			)
		)
		(duplicate_pad_numbers_are_jumpers no)
		(fp_line
			(start -1.2954 -0.5842)
			(end 1.2954 -0.5842)
			(stroke
				(width 0.1524)
				(type default)
			)
			(layer "F.SilkS")
		)
		(fp_line
			(start -1.2954 0.5842)
			(end -1.2954 -0.5842)
			(stroke
				(width 0.1524)
				(type default)
			)
			(layer "F.SilkS")
		)
		(fp_line
			(start 1.2954 -0.5842)
			(end 1.2954 0.5842)
			(stroke
				(width 0.1524)
				(type default)
			)
			(layer "F.SilkS")
		)
		(fp_line
			(start 1.2954 0.5842)
			(end -1.2954 0.5842)
			(stroke
				(width 0.1524)
				(type default)
			)
			(layer "F.SilkS")
		)
		(fp_line
			(start -1.1938 -0.406654)
			(end -0.8636 -0.406654)
			(stroke
				(width 0.1)
				(type default)
			)
			(layer "F.Fab")
		)
		(fp_line
			(start -1.1938 0.4064)
			(end -1.1938 -0.406654)
			(stroke
				(width 0.1)
				(type default)
			)
			(layer "F.Fab")
		)
		(fp_line
			(start -0.8636 -0.4572)
			(end 0.8636 -0.4572)
			(stroke
				(width 0.1)
				(type default)
			)
			(layer "F.Fab")
		)
		(fp_line
			(start -0.8636 -0.406654)
			(end -0.8636 -0.4572)
			(stroke
				(width 0.1)
				(type default)
			)
			(layer "F.Fab")
		)
		(fp_line
			(start -0.8636 0.4064)
			(end -1.1938 0.4064)
			(stroke
				(width 0.1)
				(type default)
			)
			(layer "F.Fab")
		)
		(fp_line
			(start -0.8636 0.4318)
			(end -0.8636 0.4064)
			(stroke
				(width 0.1)
				(type default)
			)
			(layer "F.Fab")
		)
		(fp_line
			(start -0.8636 0.4572)
			(end -0.8636 0.4318)
			(stroke
				(width 0.1)
				(type default)
			)
			(layer "F.Fab")
		)
		(fp_line
			(start 0.8636 -0.4572)
			(end 0.8636 -0.406654)
			(stroke
				(width 0.1)
				(type default)
			)
			(layer "F.Fab")
		)
		(fp_line
			(start 0.8636 -0.406654)
			(end 1.1938 -0.406654)
			(stroke
				(width 0.1)
				(type default)
			)
			(layer "F.Fab")
		)
		(fp_line
			(start 0.8636 0.4064)
			(end 0.8636 0.4572)
			(stroke
				(width 0.1)
				(type default)
			)
			(layer "F.Fab")
		)
		(fp_line
			(start 0.8636 0.4572)
			(end -0.8636 0.4572)
			(stroke
				(width 0.1)
				(type default)
			)
			(layer "F.Fab")
		)
		(fp_line
			(start 1.1938 -0.406654)
			(end 1.1938 0.4064)
			(stroke
				(width 0.1)
				(type default)
			)
			(layer "F.Fab")
		)
		(fp_line
			(start 1.1938 0.4064)
			(end 0.8636 0.4064)
			(stroke
				(width 0.1)
				(type default)
			)
			(layer "F.Fab")
		)
		(pad "1" smd rect
			(at -0.7366 0 270)
			(size 0.7112 0.8128)
			(layers "F.Cu" "F.Mask" "F.Paste")
			(net "P52V_HS_1272_S_N")
		)
		(pad "2" smd rect
			(at 0.7366 0 270)
			(size 0.7112 0.8128)
			(layers "F.Cu" "F.Mask" "F.Paste")
			(net "P52V_HS1_SENSE_N_R1")
		)
	)
	(footprint ""
		(layer "F.Cu")
		(at 166.543736 -65.024 180)
		(property "Reference" "PR7036"
			(at 0 0 180)
			(layer "F.SilkS")
			(hide yes)
			(effects
				(font
					(size 1.27 1.27)
				)
			)
		)
		(property "Value" ""
			(at 0 0 180)
			(layer "F.Fab")
			(effects
				(font
					(size 1.27 1.27)
				)
			)
		)
		(duplicate_pad_numbers_are_jumpers no)
		(fp_line
			(start 0.7874 0.4064)
			(end -0.7874 0.4064)
			(stroke
				(width 0.1524)
				(type default)
			)
			(layer "F.SilkS")
		)
		(fp_line
			(start 0.7874 -0.4064)
			(end 0.7874 0.4064)
			(stroke
				(width 0.1524)
				(type default)
			)
			(layer "F.SilkS")
		)
		(fp_line
			(start -0.7874 0.4064)
			(end -0.7874 -0.4064)
			(stroke
				(width 0.1524)
				(type default)
			)
			(layer "F.SilkS")
		)
		(fp_line
			(start -0.7874 -0.4064)
			(end 0.7874 -0.4064)
			(stroke
				(width 0.1524)
				(type default)
			)
			(layer "F.SilkS")
		)
		(fp_line
			(start 0.67945 0.3048)
			(end 0.120396 0.3048)
			(stroke
				(width 0.1)
				(type default)
			)
			(layer "F.Fab")
		)
		(fp_line
			(start 0.67945 -0.3048)
			(end 0.67945 0.3048)
			(stroke
				(width 0.1)
				(type default)
			)
			(layer "F.Fab")
		)
		(fp_line
			(start 0.12065 -0.2794)
			(end 0.12065 -0.3048)
			(stroke
				(width 0.1)
				(type default)
			)
			(layer "F.Fab")
		)
		(fp_line
			(start 0.12065 -0.3048)
			(end 0.67945 -0.3048)
			(stroke
				(width 0.1)
				(type default)
			)
			(layer "F.Fab")
		)
		(fp_line
			(start 0.120396 0.3048)
			(end 0.120396 0.2794)
			(stroke
				(width 0.1)
				(type default)
			)
			(layer "F.Fab")
		)
		(fp_line
			(start 0.120396 0.2794)
			(end -0.12065 0.2794)
			(stroke
				(width 0.1)
				(type default)
			)
			(layer "F.Fab")
		)
		(fp_line
			(start -0.12065 0.3048)
			(end -0.67945 0.3048)
			(stroke
				(width 0.1)
				(type default)
			)
			(layer "F.Fab")
		)
		(fp_line
			(start -0.12065 0.2794)
			(end -0.12065 0.3048)
			(stroke
				(width 0.1)
				(type default)
			)
			(layer "F.Fab")
		)
		(fp_line
			(start -0.12065 -0.2794)
			(end 0.12065 -0.2794)
			(stroke
				(width 0.1)
				(type default)
			)
			(layer "F.Fab")
		)
		(fp_line
			(start -0.12065 -0.305054)
			(end -0.12065 -0.2794)
			(stroke
				(width 0.1)
				(type default)
			)
			(layer "F.Fab")
		)
		(fp_line
			(start -0.67945 0.3048)
			(end -0.67945 -0.305054)
			(stroke
				(width 0.1)
				(type default)
			)
			(layer "F.Fab")
		)
		(fp_line
			(start -0.67945 -0.305054)
			(end -0.12065 -0.305054)
			(stroke
				(width 0.1)
				(type default)
			)
			(layer "F.Fab")
		)
		(pad "1" smd circle
			(at -0.40005 0 180)
			(size 0 0)
			(layers "F.Cu" "F.Mask" "F.Paste")
			(net "P52V_HS2_EFAULT")
		)
		(pad "2" smd circle
			(at 0.40005 0 180)
			(size 0 0)
			(layers "F.Cu" "F.Mask" "F.Paste")
			(net "GND1_FIELD_SIGNAL")
		)
	)
)
